# BASEBOARD_FAB2 (Tioga Pass) — schematic netlist excerpt (pin names and nets, part order shuffled) for the footprints in the layout excerpt that follows; sources: Cadence DE-HDL packaged netlist, KiCad conversion of Wiwynn_Tioga_Pass_MB.brd

J4G1  SCONN288_H44441004  SCONN  pkg PIP  page 43
  \12v\(1)  = P12V_NVDIMM_ABC
  VSS(93)  = GND
  DQ(4)  = M_A_DQ<5>
  VSS(92)  = GND
  DQ(0)  = M_A_DQ<1>
  VSS(91)  = GND
  DQS9P  = M_A_DQS_DP<9>
  DQS9N  = M_A_DQS_DN<9>
  VSS(90)  = GND
  DQ(6)  = M_A_DQ<7>
  VSS(89)  = GND
  DQ(2)  = M_A_DQ<3>
  VSS(88)  = GND
  DQ(12)  = M_A_DQ<13>
  VSS(87)  = GND
  DQ(8)  = M_A_DQ<9>
  VSS(86)  = GND
  DQS10P  = M_A_DQS_DP<10>
  DQS10N  = M_A_DQS_DN<10>
  VSS(85)  = GND
  DQ(14)  = M_A_DQ<15>
  VSS(84)  = GND
  DQ(10)  = M_A_DQ<11>
  VSS(83)  = GND
  DQ(20)  = M_A_DQ<21>
  VSS(82)  = GND
  DQ(16)  = M_A_DQ<17>
  VSS(81)  = GND
  DQS11P  = M_A_DQS_DP<11>
  DQS11N  = M_A_DQS_DN<11>
  VSS(80)  = GND
  DQ(22)  = M_A_DQ<23>
  VSS(79)  = GND
  DQ(18)  = M_A_DQ<19>
  VSS(78)  = GND
  DQ(28)  = M_A_DQ<29>
  VSS(77)  = GND
  DQ(24)  = M_A_DQ<25>
  VSS(76)  = GND
  DQS12P  = M_A_DQS_DP<12>
  DQS12N  = M_A_DQS_DN<12>
  VSS(75)  = GND
  DQ(30)  = M_A_DQ<31>
  VSS(74)  = GND
  DQ(26)  = M_A_DQ<27>
  VSS(73)  = GND
  CB(4)  = M_A_ECC<5>
  VSS(72)  = GND
  CB(0)  = M_A_ECC<1>
  VSS(71)  = GND
  DQS17P  = M_A_DQS_DP<17>
  DQS17N  = M_A_DQS_DN<17>
  VSS(70)  = GND
  CB(6)  = M_A_ECC<7>
  VSS(69)  = GND
  CB(2)  = M_A_ECC<3>
  VSS(68)  = GND
  RESET_N  = M_ABC_RST_N
  VDD(25)  = PVDDQ_ABC
  CKE(0)  = M_A_CKE<0>
  VDD(24)  = PVDDQ_ABC
  ACT_N  = M_A_ACT_N
  BG(0)  = M_A_BG<0>
  VDD(23)  = PVDDQ_ABC
  A12  = M_A_MA<12>
  A9  = M_A_MA<9>
  VDD(22)  = PVDDQ_ABC
  A8  = M_A_MA<8>
  A6  = M_A_MA<6>
  VDD(21)  = PVDDQ_ABC
  A3  = M_A_MA<3>
  A1  = M_A_MA<1>
  VDD(20)  = PVDDQ_ABC
  CK0P  = M_A_CLK_DP<0>
  CK0N  = M_A_CLK_DN<0>
  VDD(19)  = PVDDQ_ABC
  VTT(1)  = PVTT_ABC
  EVENT_N  = FM_DIMM_EVENT_COD_N
  A0  = M_A_MA<0>
  VDD(18)  = PVDDQ_ABC
  BA(0)  = M_A_BA<0>
  A16_RAS_N  = M_A_MA<16>
  VDD(17)  = PVDDQ_ABC
  S0_N  = M_A_CS_N<0>
  VDD(16)  = PVDDQ_ABC
  A15_CAS_N  = M_A_MA<15>
  ODT(0)  = M_A_ODT<0>
  VDD(15)  = PVDDQ_ABC
  S1_N  = M_A_CS_N<1>
  VDD(14)  = PVDDQ_ABC
  ODT(1)  = M_A_ODT<1>
  VDD(13)  = PVDDQ_ABC
  S2_N_C(0)  = M_A_CS_N<2>
  VSS(67)  = GND
  DQ(36)  = M_A_DQ<37>
  VSS(66)  = GND
  DQ(32)  = M_A_DQ<33>
  VSS(65)  = GND
  DQS13P  = M_A_DQS_DP<13>
  DQS13N  = M_A_DQS_DN<13>
  VSS(64)  = GND
  DQ(38)  = M_A_DQ<39>
  VSS(63)  = GND
  DQ(34)  = M_A_DQ<35>
  VSS(62)  = GND
  DQ(44)  = M_A_DQ<45>
  VSS(61)  = GND
  DQ(40)  = M_A_DQ<41>
  VSS(60)  = GND
  DQS14P  = M_A_DQS_DP<14>
  DQS14N  = M_A_DQS_DN<14>
  VSS(59)  = GND
  DQ(46)  = M_A_DQ<47>
  VSS(58)  = GND
  DQ(42)  = M_A_DQ<43>
  VSS(57)  = GND
  DQ(52)  = M_A_DQ<53>
  VSS(56)  = GND
  DQ(48)  = M_A_DQ<49>
  VSS(55)  = GND
  DQS15P  = M_A_DQS_DP<15>
  DQS15N  = M_A_DQS_DN<15>
  VSS(54)  = GND
  DQ(54)  = M_A_DQ<55>
  VSS(53)  = GND
  DQ(50)  = M_A_DQ<51>
  VSS(52)  = GND
  DQ(60)  = M_A_DQ<61>
  VSS(51)  = GND
  DQ(56)  = M_A_DQ<57>
  VSS(50)  = GND
  DQS16P  = M_A_DQS_DP<16>
  DQS16N  = M_A_DQS_DN<16>
  VSS(49)  = GND
  DQ(62)  = M_A_DQ<63>
  VSS(48)  = GND
  DQ(58)  = M_A_DQ<59>
  VSS(47)  = GND
  SA(0)  = GND
  SA(1)  = GND
  SCL  = SMB_DDR_ABC_VPP_SCL
  VPP(4)  = PVPP_ABC
  VPP(3)  = PVPP_ABC
  RFU(2)  = TP_CH_A_DIMM_A0_RFU_2
  \12v\(0)  = P12V_NVDIMM_ABC
  VREFCA  = M_A_VREF
  VSS(46)  = GND
  DQ(5)  = M_A_DQ<4>
  VSS(45)  = GND
  DQ(1)  = M_A_DQ<0>
  VSS(44)  = GND
  DQS0N  = M_A_DQS_DN<0>
  DQS0P  = M_A_DQS_DP<0>
  VSS(43)  = GND
  DQ(7)  = M_A_DQ<6>
  VSS(42)  = GND
  DQ(3)  = M_A_DQ<2>
  VSS(41)  = GND
  DQ(13)  = M_A_DQ<12>
  VSS(40)  = GND
  DQ(9)  = M_A_DQ<8>
  VSS(39)  = GND
  DQS1N  = M_A_DQS_DN<1>
  DQS1P  = M_A_DQS_DP<1>
  VSS(38)  = GND
  DQ(15)  = M_A_DQ<14>
  VSS(37)  = GND
  DQ(11)  = M_A_DQ<10>
  VSS(36)  = GND
  DQ(21)  = M_A_DQ<20>
  VSS(35)  = GND
  DQ(17)  = M_A_DQ<16>
  VSS(34)  = GND
  DQS2N  = M_A_DQS_DN<2>
  DQS2P  = M_A_DQS_DP<2>
  VSS(33)  = GND
  DQ(23)  = M_A_DQ<22>
  VSS(32)  = GND
  DQ(19)  = M_A_DQ<18>
  VSS(31)  = GND
  DQ(29)  = M_A_DQ<28>
  VSS(30)  = GND
  DQ(25)  = M_A_DQ<24>
  VSS(29)  = GND
  DQS3N  = M_A_DQS_DN<3>
  DQS3P  = M_A_DQS_DP<3>
  VSS(28)  = GND
  DQ(31)  = M_A_DQ<30>
  VSS(27)  = GND
  DQ(27)  = M_A_DQ<26>
  VSS(26)  = GND
  CB(5)  = M_A_ECC<4>
  VSS(25)  = GND
  CB(1)  = M_A_ECC<0>
  VSS(24)  = GND
  DQS8N  = M_A_DQS_DN<8>
  DQS8P  = M_A_DQS_DP<8>
  VSS(23)  = GND
  CB(7)  = M_A_ECC<6>
  VSS(22)  = GND
  CB(3)  = M_A_ECC<2>
  VSS(21)  = GND
  CKE(1)  = M_A_CKE<1>
  VDD(12)  = PVDDQ_ABC
  RFU(0)  = TP_CH_A_DIMM_A0_RFU_0
  VDD(11)  = PVDDQ_ABC
  BG(1)  = M_A_BG<1>
  ALERT_N  = M_A_ALERT_N
  VDD(10)  = PVDDQ_ABC
  A11  = M_A_MA<11>
  A7  = M_A_MA<7>
  VDD(9)  = PVDDQ_ABC
  A5  = M_A_MA<5>
  A4  = M_A_MA<4>
  VDD(8)  = PVDDQ_ABC
  A2  = M_A_MA<2>
  VDD(7)  = PVDDQ_ABC
  CK1P  = M_A_CLK_DP<1>
  CK1N  = M_A_CLK_DN<1>
  VDD(6)  = PVDDQ_ABC
  VTT(0)  = PVTT_ABC
  PAR  = M_A_PAR
  VDD(5)  = PVDDQ_ABC
  BA(1)  = M_A_BA<1>
  A10  = M_A_MA<10>
  VDD(4)  = PVDDQ_ABC
  RFU(1)  = TP_CH_A_DIMM_A0_RFU_1
  A14_WE_N  = M_A_MA<14>
  VDD(3)  = PVDDQ_ABC
  SAVE_N_NC  = FM_ADR_COMPLETE_ABC_N
  VDD(2)  = PVDDQ_ABC
  A13  = M_A_MA<13>
  VDD(1)  = PVDDQ_ABC
  A17  = M_A_MA<17>
  C(2)  = M_A_C<2>
  VDD(0)  = PVDDQ_ABC
  S3_N_C(1)  = M_A_CS_N<3>
  SA(2)  = GND
  VSS(20)  = GND
  DQ(37)  = M_A_DQ<36>
  VSS(19)  = GND
  DQ(33)  = M_A_DQ<32>
  VSS(18)  = GND
  DQS4N  = M_A_DQS_DN<4>
  DQS4P  = M_A_DQS_DP<4>
  VSS(17)  = GND
  DQ(39)  = M_A_DQ<38>
  VSS(16)  = GND
  DQ(35)  = M_A_DQ<34>
  VSS(15)  = GND
  DQ(45)  = M_A_DQ<44>
  VSS(14)  = GND
  DQ(41)  = M_A_DQ<40>
  VSS(13)  = GND
  DQS5N  = M_A_DQS_DN<5>
  DQS5P  = M_A_DQS_DP<5>
  VSS(12)  = GND
  DQ(47)  = M_A_DQ<46>
  VSS(11)  = GND
  DQ(43)  = M_A_DQ<42>
  VSS(10)  = GND
  DQ(53)  = M_A_DQ<52>
  VSS(9)  = GND
  DQ(49)  = M_A_DQ<48>
  VSS(8)  = GND
  DQS6N  = M_A_DQS_DN<6>
  DQS6P  = M_A_DQS_DP<6>
  VSS(7)  = GND
  DQ(55)  = M_A_DQ<54>
  VSS(6)  = GND
  DQ(51)  = M_A_DQ<50>
  VSS(5)  = GND
  DQ(61)  = M_A_DQ<60>
  VSS(4)  = GND
  DQ(57)  = M_A_DQ<56>
  VSS(3)  = GND
  DQS7N  = M_A_DQS_DN<7>
  DQS7P  = M_A_DQS_DP<7>
  VSS(2)  = GND
  DQ(63)  = M_A_DQ<62>
  VSS(1)  = GND
  DQ(59)  = M_A_DQ<58>
  VSS(0)  = GND
  VDDSPD  = PVPP_ABC
  SDA  = SMB_DDR_ABC_VPP_SDA
  VPP(1)  = PVPP_ABC
  VPP(0)  = PVPP_ABC
  VPP(2)  = PVPP_ABC

(kicad_pcb
	(version 20260206)
	(generator "pcbnew")
	(generator_version "10.0")
	(general
		(thickness 1.6)
		(legacy_teardrops no)
	)
	(paper "A4")
	(title_block
		(title "Wiwynn_Tioga_Pass_MB.brd")
		(comment 1 "Tioga Pass / footprint 2167 of 4770 (J4G1), pads 153-202 of 291")
	)
	(layers
		(0 "F.Cu" signal "TOP")
		(4 "In1.Cu" signal "L2GND")
		(6 "In2.Cu" signal "L3")
		(8 "In3.Cu" signal "L4GND")
		(10 "In4.Cu" signal "L5")
		(12 "In5.Cu" signal "L6GND")
		(14 "In6.Cu" signal "L7VCC")
		(16 "In7.Cu" signal "L8VCC")
		(18 "In8.Cu" signal "L9GND")
		(20 "In9.Cu" signal "L10")
		(22 "In10.Cu" signal "L11GND")
		(24 "In11.Cu" signal "L12")
		(26 "In12.Cu" signal "L13GND")
		(2 "B.Cu" signal "BOTTOM")
		(9 "F.Adhes" user "F.Adhesive")
		(11 "B.Adhes" user "B.Adhesive")
		(13 "F.Paste" user "Package Geometry/Pastemask Top")
		(15 "B.Paste" user "Package Geometry/Pastemask Bottom")
		(5 "F.SilkS" user "Ref Des/Silkscreen Top")
		(7 "B.SilkS" user "Ref Des/Silkscreen Bottom")
		(1 "F.Mask" user "Board Geometry/Soldermask Top")
		(3 "B.Mask" user "Board Geometry/Soldermask Bottom")
		(17 "Dwgs.User" user "User.Drawings")
		(19 "Cmts.User" user "User.Comments")
		(21 "Eco1.User" user "User.Eco1")
		(23 "Eco2.User" user "User.Eco2")
		(25 "Edge.Cuts" user "Board Geometry/Outline")
		(27 "Margin" user)
		(31 "F.CrtYd" user "Package Geometry/Place Bound Top")
		(29 "B.CrtYd" user "Package Geometry/Place Bound Bottom")
		(35 "F.Fab" user "Ref Des/Assembly Top")
		(33 "B.Fab" user "Ref Des/Assembly Bottom")
	)
	(footprint ""
		(layer "F.Cu")
		(at 194.700398 -15.423642 90)
		(property "Reference" "J4G1"
			(at 9.060688 37.32911 0)
			(unlocked yes)
			(layer "F.SilkS")
			(effects
				(font
					(size 0.7874 0.5842)
					(thickness 0.1524)
				)
				(justify left)
			)
		)
		(property "Value" ""
			(at 0 0 90)
			(layer "F.Fab")
			(effects
				(font
					(size 1.27 1.27)
				)
			)
		)
		(duplicate_pad_numbers_are_jumpers no)
		(pad "150" smd rect
			(at 4.59994 4.249928 90)
			(size 1.8034 0.508)
			(layers "F.Cu" "F.Mask" "F.Paste")
			(net "M_A_DQ<0>")
		)
		(pad "151" smd rect
			(at 4.59994 5.100066 90)
			(size 1.8034 0.508)
			(layers "F.Cu" "F.Mask" "F.Paste")
			(net "GND")
		)
		(pad "152" smd rect
			(at 4.59994 5.94995 90)
			(size 1.8034 0.508)
			(layers "F.Cu" "F.Mask" "F.Paste")
			(net "M_A_DQS_DN<0>")
		)
		(pad "153" smd rect
			(at 4.59994 6.800088 90)
			(size 1.8034 0.508)
			(layers "F.Cu" "F.Mask" "F.Paste")
			(net "M_A_DQS_DP<0>")
		)
		(pad "154" smd rect
			(at 4.59994 7.649972 90)
			(size 1.8034 0.508)
			(layers "F.Cu" "F.Mask" "F.Paste")
			(net "GND")
		)
		(pad "155" smd rect
			(at 4.59994 8.50011 90)
			(size 1.8034 0.508)
			(layers "F.Cu" "F.Mask" "F.Paste")
			(net "M_A_DQ<6>")
		)
		(pad "156" smd rect
			(at 4.59994 9.349994 90)
			(size 1.8034 0.508)
			(layers "F.Cu" "F.Mask" "F.Paste")
			(net "GND")
		)
		(pad "157" smd rect
			(at 4.59994 10.199878 90)
			(size 1.8034 0.508)
			(layers "F.Cu" "F.Mask" "F.Paste")
			(net "M_A_DQ<2>")
		)
		(pad "158" smd rect
			(at 4.59994 11.050016 90)
			(size 1.8034 0.508)
			(layers "F.Cu" "F.Mask" "F.Paste")
			(net "GND")
		)
		(pad "159" smd rect
			(at 4.59994 11.8999 90)
			(size 1.8034 0.508)
			(layers "F.Cu" "F.Mask" "F.Paste")
			(net "M_A_DQ<12>")
		)
		(pad "160" smd rect
			(at 4.59994 12.750038 90)
			(size 1.8034 0.508)
			(layers "F.Cu" "F.Mask" "F.Paste")
			(net "GND")
		)
		(pad "161" smd rect
			(at 4.59994 13.599922 90)
			(size 1.8034 0.508)
			(layers "F.Cu" "F.Mask" "F.Paste")
			(net "M_A_DQ<8>")
		)
		(pad "162" smd rect
			(at 4.59994 14.45006 90)
			(size 1.8034 0.508)
			(layers "F.Cu" "F.Mask" "F.Paste")
			(net "GND")
		)
		(pad "163" smd rect
			(at 4.59994 15.299944 90)
			(size 1.8034 0.508)
			(layers "F.Cu" "F.Mask" "F.Paste")
			(net "M_A_DQS_DN<1>")
		)
		(pad "164" smd rect
			(at 4.59994 16.150082 90)
			(size 1.8034 0.508)
			(layers "F.Cu" "F.Mask" "F.Paste")
			(net "M_A_DQS_DP<1>")
		)
		(pad "165" smd rect
			(at 4.59994 16.999966 90)
			(size 1.8034 0.508)
			(layers "F.Cu" "F.Mask" "F.Paste")
			(net "GND")
		)
		(pad "166" smd rect
			(at 4.59994 17.850104 90)
			(size 1.8034 0.508)
			(layers "F.Cu" "F.Mask" "F.Paste")
			(net "M_A_DQ<14>")
		)
		(pad "167" smd rect
			(at 4.59994 18.699988 90)
			(size 1.8034 0.508)
			(layers "F.Cu" "F.Mask" "F.Paste")
			(net "GND")
		)
		(pad "168" smd rect
			(at 4.59994 19.550126 90)
			(size 1.8034 0.508)
			(layers "F.Cu" "F.Mask" "F.Paste")
			(net "M_A_DQ<10>")
		)
		(pad "169" smd rect
			(at 4.59994 20.40001 90)
			(size 1.8034 0.508)
			(layers "F.Cu" "F.Mask" "F.Paste")
			(net "GND")
		)
		(pad "170" smd rect
			(at 4.59994 21.249894 90)
			(size 1.8034 0.508)
			(layers "F.Cu" "F.Mask" "F.Paste")
			(net "M_A_DQ<20>")
		)
		(pad "171" smd rect
			(at 4.59994 22.100032 90)
			(size 1.8034 0.508)
			(layers "F.Cu" "F.Mask" "F.Paste")
			(net "GND")
		)
		(pad "172" smd rect
			(at 4.59994 22.949916 90)
			(size 1.8034 0.508)
			(layers "F.Cu" "F.Mask" "F.Paste")
			(net "M_A_DQ<16>")
		)
		(pad "173" smd rect
			(at 4.59994 23.800054 90)
			(size 1.8034 0.508)
			(layers "F.Cu" "F.Mask" "F.Paste")
			(net "GND")
		)
		(pad "174" smd rect
			(at 4.59994 24.649938 90)
			(size 1.8034 0.508)
			(layers "F.Cu" "F.Mask" "F.Paste")
			(net "M_A_DQS_DN<2>")
		)
		(pad "175" smd rect
			(at 4.59994 25.500076 90)
			(size 1.8034 0.508)
			(layers "F.Cu" "F.Mask" "F.Paste")
			(net "M_A_DQS_DP<2>")
		)
		(pad "176" smd rect
			(at 4.59994 26.34996 90)
			(size 1.8034 0.508)
			(layers "F.Cu" "F.Mask" "F.Paste")
			(net "GND")
		)
		(pad "177" smd rect
			(at 4.59994 27.200098 90)
			(size 1.8034 0.508)
			(layers "F.Cu" "F.Mask" "F.Paste")
			(net "M_A_DQ<22>")
		)
		(pad "178" smd rect
			(at 4.59994 28.049982 90)
			(size 1.8034 0.508)
			(layers "F.Cu" "F.Mask" "F.Paste")
			(net "GND")
		)
		(pad "179" smd rect
			(at 4.59994 28.90012 90)
			(size 1.8034 0.508)
			(layers "F.Cu" "F.Mask" "F.Paste")
			(net "M_A_DQ<18>")
		)
		(pad "180" smd rect
			(at 4.59994 29.750004 90)
			(size 1.8034 0.508)
			(layers "F.Cu" "F.Mask" "F.Paste")
			(net "GND")
		)
		(pad "181" smd rect
			(at 4.59994 30.599888 90)
			(size 1.8034 0.508)
			(layers "F.Cu" "F.Mask" "F.Paste")
			(net "M_A_DQ<28>")
		)
		(pad "182" smd rect
			(at 4.59994 31.450026 90)
			(size 1.8034 0.508)
			(layers "F.Cu" "F.Mask" "F.Paste")
			(net "GND")
		)
		(pad "183" smd rect
			(at 4.59994 32.29991 90)
			(size 1.8034 0.508)
			(layers "F.Cu" "F.Mask" "F.Paste")
			(net "M_A_DQ<24>")
		)
		(pad "184" smd rect
			(at 4.59994 33.150048 90)
			(size 1.8034 0.508)
			(layers "F.Cu" "F.Mask" "F.Paste")
			(net "GND")
		)
		(pad "185" smd rect
			(at 4.59994 33.999932 90)
			(size 1.8034 0.508)
			(layers "F.Cu" "F.Mask" "F.Paste")
			(net "M_A_DQS_DN<3>")
		)
		(pad "186" smd rect
			(at 4.59994 34.85007 90)
			(size 1.8034 0.508)
			(layers "F.Cu" "F.Mask" "F.Paste")
			(net "M_A_DQS_DP<3>")
		)
		(pad "187" smd rect
			(at 4.59994 35.699954 90)
			(size 1.8034 0.508)
			(layers "F.Cu" "F.Mask" "F.Paste")
			(net "GND")
		)
		(pad "188" smd rect
			(at 4.59994 36.550092 90)
			(size 1.8034 0.508)
			(layers "F.Cu" "F.Mask" "F.Paste")
			(net "M_A_DQ<30>")
		)
		(pad "189" smd rect
			(at 4.59994 37.399976 90)
			(size 1.8034 0.508)
			(layers "F.Cu" "F.Mask" "F.Paste")
			(net "GND")
		)
		(pad "190" smd rect
			(at 4.59994 38.250114 90)
			(size 1.8034 0.508)
			(layers "F.Cu" "F.Mask" "F.Paste")
			(net "M_A_DQ<26>")
		)
		(pad "191" smd rect
			(at 4.59994 39.099998 90)
			(size 1.8034 0.508)
			(layers "F.Cu" "F.Mask" "F.Paste")
			(net "GND")
		)
		(pad "192" smd rect
			(at 4.59994 39.949882 90)
			(size 1.8034 0.508)
			(layers "F.Cu" "F.Mask" "F.Paste")
			(net "M_A_ECC<4>")
		)
		(pad "193" smd rect
			(at 4.59994 40.80002 90)
			(size 1.8034 0.508)
			(layers "F.Cu" "F.Mask" "F.Paste")
			(net "GND")
		)
		(pad "194" smd rect
			(at 4.59994 41.649904 90)
			(size 1.8034 0.508)
			(layers "F.Cu" "F.Mask" "F.Paste")
			(net "M_A_ECC<0>")
		)
		(pad "195" smd rect
			(at 4.59994 42.500042 90)
			(size 1.8034 0.508)
			(layers "F.Cu" "F.Mask" "F.Paste")
			(net "GND")
		)
		(pad "196" smd rect
			(at 4.59994 43.349926 90)
			(size 1.8034 0.508)
			(layers "F.Cu" "F.Mask" "F.Paste")
			(net "M_A_DQS_DN<8>")
		)
		(pad "197" smd rect
			(at 4.59994 44.200064 90)
			(size 1.8034 0.508)
			(layers "F.Cu" "F.Mask" "F.Paste")
			(net "M_A_DQS_DP<8>")
		)
		(pad "198" smd rect
			(at 4.59994 45.049948 90)
			(size 1.8034 0.508)
			(layers "F.Cu" "F.Mask" "F.Paste")
			(net "GND")
		)
		(pad "199" smd rect
			(at 4.59994 45.900086 90)
			(size 1.8034 0.508)
			(layers "F.Cu" "F.Mask" "F.Paste")
			(net "M_A_ECC<6>")
		)
	)
)
